(kicad_pcb
	(version 20240108)
	(generator "pcbnew")
	(generator_version "8.0")
	(general
		(thickness 1.62)
		(legacy_teardrops no)
	)
	(paper "A4")
	(title_block
		(title "Jetson Orin Baseboard")
		(date "2025-03-12")
		(rev "1.3.4")
		(company "Antmicro Ltd")
		(comment 1 "www.antmicro.com")
		(comment 9 "footprints 336-340 of 677")
	)
	(layers
		(0 "F.Cu" signal)
		(1 "In1.Cu" signal)
		(2 "In2.Cu" signal)
		(3 "In3.Cu" signal)
		(4 "In4.Cu" jumper)
		(5 "In5.Cu" signal)
		(6 "In6.Cu" signal)
		(31 "B.Cu" signal)
		(32 "B.Adhes" user "B.Adhesive")
		(33 "F.Adhes" user "F.Adhesive")
		(34 "B.Paste" user)
		(35 "F.Paste" user)
		(36 "B.SilkS" user "B.Silkscreen")
		(37 "F.SilkS" user "F.Silkscreen")
		(38 "B.Mask" user)
		(39 "F.Mask" user)
		(40 "Dwgs.User" user "User.Drawings")
		(41 "Cmts.User" user "User.Comments")
		(42 "Eco1.User" user "User.Eco1")
		(43 "Eco2.User" user "User.Eco2")
		(44 "Edge.Cuts" user)
		(45 "Margin" user)
		(46 "B.CrtYd" user "B.Courtyard")
		(47 "F.CrtYd" user "F.Courtyard")
		(48 "B.Fab" user)
		(49 "F.Fab" user)
	)
	(footprint "antmicro-footprints:C_0402_1005Metric"
		(layer "B.Cu")
		(at 47.54 111.25 -90)
		(descr "Capacitor SMD 0402")
		(tags "capacitor SMD 0402")
		(property "Reference" "C158"
			(at -2 0.7 -90)
			(layer "B.SilkS")
			(effects
				(font
					(size 0.7 0.7)
					(thickness 0.15)
				)
				(justify left bottom mirror)
			)
		)
		(property "Value" "C_100n_0402"
			(at -1.022927 -2.155213 90)
			(layer "B.Fab")
			(effects
				(font
					(size 0.7 0.7)
					(thickness 0.15)
				)
				(justify left bottom mirror)
			)
		)
		(property "Footprint" "antmicro-footprints:C_0402_1005Metric"
			(at 0 0 -90)
			(layer "F.Fab")
			(hide yes)
			(effects
				(font
					(size 1.27 1.27)
					(thickness 0.15)
				)
			)
		)
		(property "Datasheet" "https://www.murata.com/products/productdetail?partno=GRM155R61H104KE14%23"
			(at 0 0 -90)
			(layer "F.Fab")
			(hide yes)
			(effects
				(font
					(size 1.27 1.27)
					(thickness 0.15)
				)
			)
		)
		(property "Author" "Antmicro"
			(at -63.71 158.79 0)
			(layer "B.Fab")
			(hide yes)
			(effects
				(font
					(size 1 1)
					(thickness 0.15)
				)
				(justify mirror)
			)
		)
		(property "Dielectric" "X5R"
			(at -63.71 158.79 0)
			(layer "B.Fab")
			(hide yes)
			(effects
				(font
					(size 1 1)
					(thickness 0.15)
				)
				(justify mirror)
			)
		)
		(property "License" "Apache-2.0"
			(at -63.71 158.79 0)
			(layer "B.Fab")
			(hide yes)
			(effects
				(font
					(size 1 1)
					(thickness 0.15)
				)
				(justify mirror)
			)
		)
		(property "MPN" "GRM155R61H104KE14D"
			(at -63.71 158.79 0)
			(layer "B.Fab")
			(hide yes)
			(effects
				(font
					(size 1 1)
					(thickness 0.15)
				)
				(justify mirror)
			)
		)
		(property "Manufacturer" "Murata"
			(at -63.71 158.79 0)
			(layer "B.Fab")
			(hide yes)
			(effects
				(font
					(size 1 1)
					(thickness 0.15)
				)
				(justify mirror)
			)
		)
		(property "Val" "100n"
			(at -63.71 158.79 0)
			(layer "B.Fab")
			(hide yes)
			(effects
				(font
					(size 1 1)
					(thickness 0.15)
				)
				(justify mirror)
			)
		)
		(property "Voltage" "50V"
			(at -63.71 158.79 0)
			(layer "B.Fab")
			(hide yes)
			(effects
				(font
					(size 1 1)
					(thickness 0.15)
				)
				(justify mirror)
			)
		)
		(sheetname "USB Debug, DP")
		(sheetfile "usb.kicad_sch")
		(attr smd)
		(fp_rect
			(start -0.925 0.47)
			(end 0.925 -0.47)
			(stroke
				(width 0.05)
				(type default)
			)
			(fill none)
			(layer "B.CrtYd")
		)
		(fp_line
			(start -0.494 0.25)
			(end -0.494 -0.248)
			(stroke
				(width 0.15)
				(type solid)
			)
			(layer "B.Fab")
		)
		(fp_line
			(start 0.504 0.25)
			(end -0.494 0.25)
			(stroke
				(width 0.15)
				(type solid)
			)
			(layer "B.Fab")
		)
		(fp_line
			(start -0.494 -0.248)
			(end 0.504 -0.248)
			(stroke
				(width 0.15)
				(type solid)
			)
			(layer "B.Fab")
		)
		(fp_line
			(start 0.504 -0.248)
			(end 0.504 0.25)
			(stroke
				(width 0.15)
				(type solid)
			)
			(layer "B.Fab")
		)
		(fp_text user "Author: Antmicro"
			(at -0.939 -3.399 90)
			(layer "B.Fab")
			(hide yes)
			(effects
				(font
					(size 0.7 0.7)
					(thickness 0.15)
				)
				(justify left bottom mirror)
			)
		)
		(fp_text user "License: Apache-2.0"
			(at -0.939 -5.799 90)
			(layer "B.Fab")
			(hide yes)
			(effects
				(font
					(size 0.7 0.7)
					(thickness 0.15)
				)
				(justify left bottom mirror)
			)
		)
		(fp_text user "${REFERENCE}"
			(at -0.939 -4.599 90)
			(layer "B.Fab")
			(hide yes)
			(effects
				(font
					(size 0.7 0.7)
					(thickness 0.15)
				)
				(justify left bottom mirror)
			)
		)
		(pad "1" smd roundrect
			(at -0.48 0 270)
			(size 0.59 0.64)
			(layers "B.Cu" "B.Paste" "B.Mask")
			(roundrect_rratio 0.25)
			(net 185 "/USB Debug, DP/FTDI_3V3")
			(pintype "passive")
		)
		(pad "2" smd roundrect
			(at 0.48 0 270)
			(size 0.59 0.64)
			(layers "B.Cu" "B.Paste" "B.Mask")
			(roundrect_rratio 0.25)
			(net 1 "GND")
			(pintype "passive")
		)
	)
	(footprint "antmicro-footprints:C_0402_1005Metric"
		(layer "B.Cu")
		(at 54.9 116.8 90)
		(descr "Capacitor SMD 0402")
		(tags "capacitor SMD 0402")
		(property "Reference" "C146"
			(at 1.28 2.74 -90)
			(layer "B.SilkS")
			(effects
				(font
					(size 0.7 0.7)
					(thickness 0.15)
				)
				(justify left bottom mirror)
			)
		)
		(property "Value" "C_47p_0402"
			(at 0 -1.4 -90)
			(layer "B.Fab")
			(effects
				(font
					(size 0.7 0.7)
					(thickness 0.15)
				)
				(justify left bottom mirror)
			)
		)
		(property "Footprint" "antmicro-footprints:C_0402_1005Metric"
			(at 0 0 90)
			(layer "F.Fab")
			(hide yes)
			(effects
				(font
					(size 1.27 1.27)
					(thickness 0.15)
				)
			)
		)
		(property "Datasheet" "https://www.kemet.com/en/us/capacitors/product/C0402C470J5GACTU.html"
			(at 0 0 90)
			(layer "F.Fab")
			(hide yes)
			(effects
				(font
					(size 1.27 1.27)
					(thickness 0.15)
				)
			)
		)
		(property "Author" "Antmicro"
			(at 171.7 61.9 0)
			(layer "B.Fab")
			(hide yes)
			(effects
				(font
					(size 1 1)
					(thickness 0.15)
				)
				(justify mirror)
			)
		)
		(property "Dielectric" "C0G"
			(at 171.7 61.9 0)
			(layer "B.Fab")
			(hide yes)
			(effects
				(font
					(size 1 1)
					(thickness 0.15)
				)
				(justify mirror)
			)
		)
		(property "License" "Apache-2.0"
			(at 171.7 61.9 0)
			(layer "B.Fab")
			(hide yes)
			(effects
				(font
					(size 1 1)
					(thickness 0.15)
				)
				(justify mirror)
			)
		)
		(property "MPN" "C0402C470J5GACTU"
			(at 171.7 61.9 0)
			(layer "B.Fab")
			(hide yes)
			(effects
				(font
					(size 1 1)
					(thickness 0.15)
				)
				(justify mirror)
			)
		)
		(property "Manufacturer" "KEMET"
			(at 171.7 61.9 0)
			(layer "B.Fab")
			(hide yes)
			(effects
				(font
					(size 1 1)
					(thickness 0.15)
				)
				(justify mirror)
			)
		)
		(property "Val" "47p"
			(at 171.7 61.9 0)
			(layer "B.Fab")
			(hide yes)
			(effects
				(font
					(size 1 1)
					(thickness 0.15)
				)
				(justify mirror)
			)
		)
		(property "Voltage" ""
			(at 171.7 61.9 0)
			(layer "B.Fab")
			(hide yes)
			(effects
				(font
					(size 1 1)
					(thickness 0.15)
				)
				(justify mirror)
			)
		)
		(sheetname "USB Debug, DP")
		(sheetfile "usb.kicad_sch")
		(attr smd)
		(fp_rect
			(start -0.925 0.47)
			(end 0.925 -0.47)
			(stroke
				(width 0.05)
				(type default)
			)
			(fill none)
			(layer "B.CrtYd")
		)
		(fp_line
			(start 0.504 -0.248)
			(end 0.504 0.25)
			(stroke
				(width 0.15)
				(type solid)
			)
			(layer "B.Fab")
		)
		(fp_line
			(start -0.494 -0.248)
			(end 0.504 -0.248)
			(stroke
				(width 0.15)
				(type solid)
			)
			(layer "B.Fab")
		)
		(fp_line
			(start 0.504 0.25)
			(end -0.494 0.25)
			(stroke
				(width 0.15)
				(type solid)
			)
			(layer "B.Fab")
		)
		(fp_line
			(start -0.494 0.25)
			(end -0.494 -0.248)
			(stroke
				(width 0.15)
				(type solid)
			)
			(layer "B.Fab")
		)
		(fp_text user "${REFERENCE}"
			(at -0.932 -3.168 -90)
			(layer "B.Fab")
			(hide yes)
			(effects
				(font
					(size 0.7 0.7)
					(thickness 0.15)
				)
				(justify left bottom mirror)
			)
		)
		(fp_text user "License: Apache-2.0"
			(at -0.932 -5.17 -90)
			(layer "B.Fab")
			(hide yes)
			(effects
				(font
					(size 0.7 0.7)
					(thickness 0.15)
				)
				(justify left bottom mirror)
			)
		)
		(fp_text user "Author: Antmicro"
			(at -0.932 -4.17 -90)
			(layer "B.Fab")
			(hide yes)
			(effects
				(font
					(size 0.7 0.7)
					(thickness 0.15)
				)
				(justify left bottom mirror)
			)
		)
		(pad "1" smd roundrect
			(at -0.48 0 90)
			(size 0.59 0.64)
			(layers "B.Cu" "B.Paste" "B.Mask")
			(roundrect_rratio 0.25)
			(net 613 "/USB Debug, DP/USBC3_D_P")
			(pintype "passive")
		)
		(pad "2" smd roundrect
			(at 0.48 0 90)
			(size 0.59 0.64)
			(layers "B.Cu" "B.Paste" "B.Mask")
			(roundrect_rratio 0.25)
			(net 1 "GND")
			(pintype "passive")
		)
	)
	(footprint "antmicro-footprints:R_0402_1005Metric"
		(layer "B.Cu")
		(at 89.9 116.1 -90)
		(descr "Resistor SMD 0402")
		(tags "resistor SMD 0402")
		(property "Reference" "R279"
			(at -2.55 -5.15 90)
			(layer "B.SilkS")
			(effects
				(font
					(size 0.7 0.7)
					(thickness 0.15)
				)
				(justify left bottom mirror)
			)
		)
		(property "Value" "R_2k2_0402"
			(at 0 -1.4 90)
			(layer "B.Fab")
			(effects
				(font
					(size 0.7 0.7)
					(thickness 0.15)
				)
				(justify left bottom mirror)
			)
		)
		(property "Footprint" "antmicro-footprints:R_0402_1005Metric"
			(at 0 0 -90)
			(layer "F.Fab")
			(hide yes)
			(effects
				(font
					(size 1.27 1.27)
					(thickness 0.15)
				)
			)
		)
		(property "Datasheet" "https://www.bourns.com/docs/product-datasheets/cr.pdf"
			(at 0 0 -90)
			(layer "F.Fab")
			(hide yes)
			(effects
				(font
					(size 1.27 1.27)
					(thickness 0.15)
				)
			)
		)
		(property "Author" "Antmicro"
			(at -26.2 206 0)
			(layer "B.Fab")
			(hide yes)
			(effects
				(font
					(size 1 1)
					(thickness 0.15)
				)
				(justify mirror)
			)
		)
		(property "License" "Apache-2.0"
			(at -26.2 206 0)
			(layer "B.Fab")
			(hide yes)
			(effects
				(font
					(size 1 1)
					(thickness 0.15)
				)
				(justify mirror)
			)
		)
		(property "MPN" "CR0402-FX-2201GLF"
			(at -26.2 206 0)
			(layer "B.Fab")
			(hide yes)
			(effects
				(font
					(size 1 1)
					(thickness 0.15)
				)
				(justify mirror)
			)
		)
		(property "Manufacturer" "Bourns"
			(at -26.2 206 0)
			(layer "B.Fab")
			(hide yes)
			(effects
				(font
					(size 1 1)
					(thickness 0.15)
				)
				(justify mirror)
			)
		)
		(property "Tolerance" "1%"
			(at -26.2 206 0)
			(layer "B.Fab")
			(hide yes)
			(effects
				(font
					(size 1 1)
					(thickness 0.15)
				)
				(justify mirror)
			)
		)
		(property "Val" "2k2"
			(at -26.2 206 0)
			(layer "B.Fab")
			(hide yes)
			(effects
				(font
					(size 1 1)
					(thickness 0.15)
				)
				(justify mirror)
			)
		)
		(sheetname "HDMI")
		(sheetfile "hdmi.kicad_sch")
		(attr smd exclude_from_pos_files exclude_from_bom dnp)
		(fp_rect
			(start -0.925 0.47)
			(end 0.925 -0.47)
			(stroke
				(width 0.05)
				(type default)
			)
			(fill none)
			(layer "B.CrtYd")
		)
		(fp_rect
			(start -0.5 0.25)
			(end 0.5 -0.25)
			(stroke
				(width 0.15)
				(type solid)
			)
			(fill none)
			(layer "B.Fab")
		)
		(fp_text user "Author: Antmicro"
			(at -0.95 -4.169 90)
			(layer "B.Fab")
			(hide yes)
			(effects
				(font
					(size 0.7 0.7)
					(thickness 0.15)
				)
				(justify left bottom mirror)
			)
		)
		(fp_text user "License: Apache-2.0"
			(at -0.95 -5.169 90)
			(layer "B.Fab")
			(hide yes)
			(effects
				(font
					(size 0.7 0.7)
					(thickness 0.15)
				)
				(justify left bottom mirror)
			)
		)
		(fp_text user "${REFERENCE}"
			(at -0.95 -3.168 90)
			(layer "B.Fab")
			(hide yes)
			(effects
				(font
					(size 0.7 0.7)
					(thickness 0.15)
				)
				(justify left bottom mirror)
			)
		)
		(pad "1" smd roundrect
			(at -0.48 0 270)
			(size 0.59 0.64)
			(layers "B.Cu" "B.Paste" "B.Mask")
			(roundrect_rratio 0.25)
			(net 701 "/HDMI/HDMI_SDA_3V3")
			(pintype "passive")
		)
		(pad "2" smd roundrect
			(at 0.48 0 270)
			(size 0.59 0.64)
			(layers "B.Cu" "B.Paste" "B.Mask")
			(roundrect_rratio 0.25)
			(net 87 "+3V3")
			(pintype "passive")
		)
	)
	(footprint "antmicro-footprints:R_0402_1005Metric"
		(layer "B.Cu")
		(at 112.4 107.1 180)
		(descr "Resistor SMD 0402")
		(tags "resistor SMD 0402")
		(property "Reference" "R114"
			(at -3.72 -0.3 0)
			(layer "B.SilkS")
			(effects
				(font
					(size 0.7 0.7)
					(thickness 0.15)
				)
				(justify left bottom mirror)
			)
		)
		(property "Value" "R_0R_0402"
			(at 0 -1.4 0)
			(layer "B.Fab")
			(effects
				(font
					(size 0.7 0.7)
					(thickness 0.15)
				)
				(justify left bottom mirror)
			)
		)
		(property "Footprint" "antmicro-footprints:R_0402_1005Metric"
			(at 0 0 180)
			(layer "F.Fab")
			(hide yes)
			(effects
				(font
					(size 1.27 1.27)
					(thickness 0.15)
				)
			)
		)
		(property "Datasheet" "https://industrial.panasonic.com/cdbs/www-data/pdf/RDA0000/AOA0000C301.pdf"
			(at 0 0 180)
			(layer "F.Fab")
			(hide yes)
			(effects
				(font
					(size 1.27 1.27)
					(thickness 0.15)
				)
			)
		)
		(property "Author" "Antmicro"
			(at 224.8 214.2 0)
			(layer "B.Fab")
			(hide yes)
			(effects
				(font
					(size 1 1)
					(thickness 0.15)
				)
				(justify mirror)
			)
		)
		(property "Current" "1A"
			(at 224.8 214.2 0)
			(layer "B.Fab")
			(hide yes)
			(effects
				(font
					(size 1 1)
					(thickness 0.15)
				)
				(justify mirror)
			)
		)
		(property "License" "Apache-2.0"
			(at 224.8 214.2 0)
			(layer "B.Fab")
			(hide yes)
			(effects
				(font
					(size 1 1)
					(thickness 0.15)
				)
				(justify mirror)
			)
		)
		(property "MPN" "ERJ2GE0R00X"
			(at 224.8 214.2 0)
			(layer "B.Fab")
			(hide yes)
			(effects
				(font
					(size 1 1)
					(thickness 0.15)
				)
				(justify mirror)
			)
		)
		(property "Manufacturer" "Panasonic"
			(at 224.8 214.2 0)
			(layer "B.Fab")
			(hide yes)
			(effects
				(font
					(size 1 1)
					(thickness 0.15)
				)
				(justify mirror)
			)
		)
		(property "Tolerance" ""
			(at 224.8 214.2 0)
			(layer "B.Fab")
			(hide yes)
			(effects
				(font
					(size 1 1)
					(thickness 0.15)
				)
				(justify mirror)
			)
		)
		(property "Val" "0R"
			(at 224.8 214.2 0)
			(layer "B.Fab")
			(hide yes)
			(effects
				(font
					(size 1 1)
					(thickness 0.15)
				)
				(justify mirror)
			)
		)
		(sheetname "USB3")
		(sheetfile "usb3.kicad_sch")
		(attr smd exclude_from_pos_files exclude_from_bom dnp)
		(fp_rect
			(start -0.925 0.47)
			(end 0.925 -0.47)
			(stroke
				(width 0.05)
				(type default)
			)
			(fill none)
			(layer "B.CrtYd")
		)
		(fp_rect
			(start -0.5 0.25)
			(end 0.5 -0.25)
			(stroke
				(width 0.15)
				(type solid)
			)
			(fill none)
			(layer "B.Fab")
		)
		(fp_text user "Author: Antmicro"
			(at -0.95 -4.169 0)
			(layer "B.Fab")
			(hide yes)
			(effects
				(font
					(size 0.7 0.7)
					(thickness 0.15)
				)
				(justify left bottom mirror)
			)
		)
		(fp_text user "License: Apache-2.0"
			(at -0.95 -5.169 0)
			(layer "B.Fab")
			(hide yes)
			(effects
				(font
					(size 0.7 0.7)
					(thickness 0.15)
				)
				(justify left bottom mirror)
			)
		)
		(fp_text user "${REFERENCE}"
			(at -0.95 -3.168 0)
			(layer "B.Fab")
			(hide yes)
			(effects
				(font
					(size 0.7 0.7)
					(thickness 0.15)
				)
				(justify left bottom mirror)
			)
		)
		(pad "1" smd roundrect
			(at -0.48 0 180)
			(size 0.59 0.64)
			(layers "B.Cu" "B.Paste" "B.Mask")
			(roundrect_rratio 0.25)
			(net 1 "GND")
			(pintype "passive")
		)
		(pad "2" smd roundrect
			(at 0.48 0 180)
			(size 0.59 0.64)
			(layers "B.Cu" "B.Paste" "B.Mask")
			(roundrect_rratio 0.25)
			(net 314 "/USB3/USBC1_ADDR")
			(pintype "passive")
		)
	)
	(footprint "antmicro-footprints:R_0402_1005Metric"
		(layer "B.Cu")
		(at 90.49 101.91 45)
		(descr "Resistor SMD 0402")
		(tags "resistor SMD 0402")
		(property "Reference" "R213"
			(at -0.834386 0.424264 -135)
			(layer "B.SilkS")
			(effects
				(font
					(size 0.7 0.7)
					(thickness 0.15)
				)
				(justify left bottom mirror)
			)
		)
		(property "Value" "R_499R_0402"
			(at -1.011843 -1.772046 -135)
			(layer "B.Fab")
			(effects
				(font
					(size 0.7 0.7)
					(thickness 0.15)
				)
				(justify left bottom mirror)
			)
		)
		(property "Footprint" "antmicro-footprints:R_0402_1005Metric"
			(at 0 0 45)
			(layer "F.Fab")
			(hide yes)
			(effects
				(font
					(size 1.27 1.27)
					(thickness 0.15)
				)
			)
		)
		(property "Datasheet" "https://www.mouser.com/datasheet/2/54/cr-1858361.pdf"
			(at 0 0 45)
			(layer "F.Fab")
			(hide yes)
			(effects
				(font
					(size 1.27 1.27)
					(thickness 0.15)
				)
			)
		)
		(property "Author" "Antmicro"
			(at 98.56516 -34.137345 0)
			(layer "B.Fab")
			(hide yes)
			(effects
				(font
					(size 1 1)
					(thickness 0.15)
				)
				(justify mirror)
			)
		)
		(property "License" "Apache-2.0"
			(at 98.56516 -34.137345 0)
			(layer "B.Fab")
			(hide yes)
			(effects
				(font
					(size 1 1)
					(thickness 0.15)
				)
				(justify mirror)
			)
		)
		(property "MPN" "CR0402-FX-4990GLF"
			(at 98.56516 -34.137345 0)
			(layer "B.Fab")
			(hide yes)
			(effects
				(font
					(size 1 1)
					(thickness 0.15)
				)
				(justify mirror)
			)
		)
		(property "Manufacturer" "Bourns"
			(at 98.56516 -34.137345 0)
			(layer "B.Fab")
			(hide yes)
			(effects
				(font
					(size 1 1)
					(thickness 0.15)
				)
				(justify mirror)
			)
		)
		(property "Tolerance" "1%"
			(at 98.56516 -34.137345 0)
			(layer "B.Fab")
			(hide yes)
			(effects
				(font
					(size 1 1)
					(thickness 0.15)
				)
				(justify mirror)
			)
		)
		(property "Val" "499R"
			(at 98.56516 -34.137345 0)
			(layer "B.Fab")
			(hide yes)
			(effects
				(font
					(size 1 1)
					(thickness 0.15)
				)
				(justify mirror)
			)
		)
		(sheetname "HDMI")
		(sheetfile "hdmi.kicad_sch")
		(attr smd)
		(fp_poly
			(pts
				(xy -0.925 0.47) (xy 0.925 0.47) (xy 0.925 -0.47) (xy -0.925 -0.47)
			)
			(stroke
				(width 0.05)
				(type default)
			)
			(fill none)
			(layer "B.CrtYd")
		)
		(fp_poly
			(pts
				(xy -0.5 0.25) (xy 0.5 0.25) (xy 0.5 -0.25) (xy -0.5 -0.25)
			)
			(stroke
				(width 0.15)
				(type solid)
			)
			(fill none)
			(layer "B.Fab")
		)
		(fp_text user "${REFERENCE}"
			(at -0.95 -3.168 -135)
			(layer "B.Fab")
			(hide yes)
			(effects
				(font
					(size 0.7 0.7)
					(thickness 0.15)
				)
				(justify left bottom mirror)
			)
		)
		(fp_text user "License: Apache-2.0"
			(at -0.949999 -5.169 -135)
			(layer "B.Fab")
			(hide yes)
			(effects
				(font
					(size 0.7 0.7)
					(thickness 0.15)
				)
				(justify left bottom mirror)
			)
		)
		(fp_text user "Author: Antmicro"
			(at -0.95 -4.169 -135)
			(layer "B.Fab")
			(hide yes)
			(effects
				(font
					(size 0.7 0.7)
					(thickness 0.15)
				)
				(justify left bottom mirror)
			)
		)
		(pad "1" smd roundrect
			(at -0.48 0 45)
			(size 0.59 0.64)
			(layers "B.Cu" "B.Paste" "B.Mask")
			(roundrect_rratio 0.25)
			(net 623 "Net-(Q2-D)")
			(pintype "passive")
		)
		(pad "2" smd roundrect
			(at 0.48 0 45)
			(size 0.59 0.64)
			(layers "B.Cu" "B.Paste" "B.Mask")
			(roundrect_rratio 0.25)
			(net 493 "/HDMI/HDMI_D1_P")
			(pintype "passive")
		)
	)
)
